(kicad_pcb
	(version 20260206)
	(generator "pcbnew")
	(generator_version "10.0")
	(general
		(thickness 1.6)
		(legacy_teardrops no)
	)
	(paper "A4")
	(title_block
		(title "9054_F0T_PDB_BD_GPU_F_V04_1213_1550_OCP.brd")
		(comment 1 "Grand Teton / footprints 261-267 of 608")
	)
	(layers
		(0 "F.Cu" signal "TOP")
		(4 "In1.Cu" signal "GND")
		(6 "In2.Cu" signal "IN1")
		(8 "In3.Cu" signal "GND1")
		(10 "In4.Cu" signal "VCC")
		(12 "In5.Cu" signal "VCC1")
		(14 "In6.Cu" signal "GND2")
		(16 "In7.Cu" signal "IN2")
		(18 "In8.Cu" signal "GND3")
		(2 "B.Cu" signal "BOTTOM")
		(9 "F.Adhes" user "F.Adhesive")
		(11 "B.Adhes" user "B.Adhesive")
		(13 "F.Paste" user "Package Geometry/Pastemask Top")
		(15 "B.Paste" user "Package Geometry/Pastemask Bottom")
		(5 "F.SilkS" user "Ref Des/Silkscreen Top")
		(7 "B.SilkS" user "Ref Des/Silkscreen Bottom")
		(1 "F.Mask" user "Board Geometry/Soldermask Top")
		(3 "B.Mask" user "Board Geometry/Soldermask Bottom")
		(17 "Dwgs.User" user "User.Drawings")
		(19 "Cmts.User" user "User.Comments")
		(21 "Eco1.User" user "User.Eco1")
		(23 "Eco2.User" user "User.Eco2")
		(25 "Edge.Cuts" user "Board Geometry/Outline")
		(27 "Margin" user)
		(31 "F.CrtYd" user "Package Geometry/Place Bound Top")
		(29 "B.CrtYd" user "Package Geometry/Place Bound Bottom")
		(35 "F.Fab" user "Ref Des/Assembly Top")
		(33 "B.Fab" user "Ref Des/Assembly Bottom")
	)
	(footprint ""
		(layer "F.Cu")
		(at 145.11782 -71.755)
		(property "Reference" "PR6981"
			(at 0 0 0)
			(layer "F.SilkS")
			(hide yes)
			(effects
				(font
					(size 1.27 1.27)
				)
			)
		)
		(property "Value" ""
			(at 0 0 0)
			(layer "F.Fab")
			(effects
				(font
					(size 1.27 1.27)
				)
			)
		)
		(duplicate_pad_numbers_are_jumpers no)
		(fp_line
			(start -1.2954 -0.5842)
			(end 1.2954 -0.5842)
			(stroke
				(width 0.1524)
				(type default)
			)
			(layer "F.SilkS")
		)
		(fp_line
			(start -1.2954 0.5842)
			(end -1.2954 -0.5842)
			(stroke
				(width 0.1524)
				(type default)
			)
			(layer "F.SilkS")
		)
		(fp_line
			(start 1.2954 -0.5842)
			(end 1.2954 0.5842)
			(stroke
				(width 0.1524)
				(type default)
			)
			(layer "F.SilkS")
		)
		(fp_line
			(start 1.2954 0.5842)
			(end -1.2954 0.5842)
			(stroke
				(width 0.1524)
				(type default)
			)
			(layer "F.SilkS")
		)
		(fp_line
			(start -1.1938 -0.406654)
			(end -0.8636 -0.406654)
			(stroke
				(width 0.1)
				(type default)
			)
			(layer "F.Fab")
		)
		(fp_line
			(start -1.1938 0.4064)
			(end -1.1938 -0.406654)
			(stroke
				(width 0.1)
				(type default)
			)
			(layer "F.Fab")
		)
		(fp_line
			(start -0.8636 -0.4572)
			(end 0.8636 -0.4572)
			(stroke
				(width 0.1)
				(type default)
			)
			(layer "F.Fab")
		)
		(fp_line
			(start -0.8636 -0.406654)
			(end -0.8636 -0.4572)
			(stroke
				(width 0.1)
				(type default)
			)
			(layer "F.Fab")
		)
		(fp_line
			(start -0.8636 0.4064)
			(end -1.1938 0.4064)
			(stroke
				(width 0.1)
				(type default)
			)
			(layer "F.Fab")
		)
		(fp_line
			(start -0.8636 0.4318)
			(end -0.8636 0.4064)
			(stroke
				(width 0.1)
				(type default)
			)
			(layer "F.Fab")
		)
		(fp_line
			(start -0.8636 0.4572)
			(end -0.8636 0.4318)
			(stroke
				(width 0.1)
				(type default)
			)
			(layer "F.Fab")
		)
		(fp_line
			(start 0.8636 -0.4572)
			(end 0.8636 -0.406654)
			(stroke
				(width 0.1)
				(type default)
			)
			(layer "F.Fab")
		)
		(fp_line
			(start 0.8636 -0.406654)
			(end 1.1938 -0.406654)
			(stroke
				(width 0.1)
				(type default)
			)
			(layer "F.Fab")
		)
		(fp_line
			(start 0.8636 0.4064)
			(end 0.8636 0.4572)
			(stroke
				(width 0.1)
				(type default)
			)
			(layer "F.Fab")
		)
		(fp_line
			(start 0.8636 0.4572)
			(end -0.8636 0.4572)
			(stroke
				(width 0.1)
				(type default)
			)
			(layer "F.Fab")
		)
		(fp_line
			(start 1.1938 -0.406654)
			(end 1.1938 0.4064)
			(stroke
				(width 0.1)
				(type default)
			)
			(layer "F.Fab")
		)
		(fp_line
			(start 1.1938 0.4064)
			(end 0.8636 0.4064)
			(stroke
				(width 0.1)
				(type default)
			)
			(layer "F.Fab")
		)
		(pad "1" smd rect
			(at -0.7366 0 270)
			(size 0.7112 0.8128)
			(layers "F.Cu" "F.Mask" "F.Paste")
			(net "P52V_HS2_4287_S1P")
		)
		(pad "2" smd rect
			(at 0.7366 0 270)
			(size 0.7112 0.8128)
			(layers "F.Cu" "F.Mask" "F.Paste")
			(net "P52V_HS2_SENSE_P_R1")
		)
	)
	(footprint ""
		(layer "F.Cu")
		(at 317.2079 -83.82 180)
		(property "Reference" "PR6969"
			(at 0 0 180)
			(layer "F.SilkS")
			(hide yes)
			(effects
				(font
					(size 1.27 1.27)
				)
			)
		)
		(property "Value" ""
			(at 0 0 180)
			(layer "F.Fab")
			(effects
				(font
					(size 1.27 1.27)
				)
			)
		)
		(duplicate_pad_numbers_are_jumpers no)
		(fp_line
			(start 0.7874 0.4064)
			(end -0.7874 0.4064)
			(stroke
				(width 0.1524)
				(type default)
			)
			(layer "F.SilkS")
		)
		(fp_line
			(start 0.7874 -0.4064)
			(end 0.7874 0.4064)
			(stroke
				(width 0.1524)
				(type default)
			)
			(layer "F.SilkS")
		)
		(fp_line
			(start -0.7874 0.4064)
			(end -0.7874 -0.4064)
			(stroke
				(width 0.1524)
				(type default)
			)
			(layer "F.SilkS")
		)
		(fp_line
			(start -0.7874 -0.4064)
			(end 0.7874 -0.4064)
			(stroke
				(width 0.1524)
				(type default)
			)
			(layer "F.SilkS")
		)
		(fp_line
			(start 0.67945 0.3048)
			(end 0.120396 0.3048)
			(stroke
				(width 0.1)
				(type default)
			)
			(layer "F.Fab")
		)
		(fp_line
			(start 0.67945 -0.3048)
			(end 0.67945 0.3048)
			(stroke
				(width 0.1)
				(type default)
			)
			(layer "F.Fab")
		)
		(fp_line
			(start 0.12065 -0.2794)
			(end 0.12065 -0.3048)
			(stroke
				(width 0.1)
				(type default)
			)
			(layer "F.Fab")
		)
		(fp_line
			(start 0.12065 -0.3048)
			(end 0.67945 -0.3048)
			(stroke
				(width 0.1)
				(type default)
			)
			(layer "F.Fab")
		)
		(fp_line
			(start 0.120396 0.3048)
			(end 0.120396 0.2794)
			(stroke
				(width 0.1)
				(type default)
			)
			(layer "F.Fab")
		)
		(fp_line
			(start 0.120396 0.2794)
			(end -0.12065 0.2794)
			(stroke
				(width 0.1)
				(type default)
			)
			(layer "F.Fab")
		)
		(fp_line
			(start -0.12065 0.3048)
			(end -0.67945 0.3048)
			(stroke
				(width 0.1)
				(type default)
			)
			(layer "F.Fab")
		)
		(fp_line
			(start -0.12065 0.2794)
			(end -0.12065 0.3048)
			(stroke
				(width 0.1)
				(type default)
			)
			(layer "F.Fab")
		)
		(fp_line
			(start -0.12065 -0.2794)
			(end 0.12065 -0.2794)
			(stroke
				(width 0.1)
				(type default)
			)
			(layer "F.Fab")
		)
		(fp_line
			(start -0.12065 -0.305054)
			(end -0.12065 -0.2794)
			(stroke
				(width 0.1)
				(type default)
			)
			(layer "F.Fab")
		)
		(fp_line
			(start -0.67945 0.3048)
			(end -0.67945 -0.305054)
			(stroke
				(width 0.1)
				(type default)
			)
			(layer "F.Fab")
		)
		(fp_line
			(start -0.67945 -0.305054)
			(end -0.12065 -0.305054)
			(stroke
				(width 0.1)
				(type default)
			)
			(layer "F.Fab")
		)
		(pad "1" smd rect
			(at -0.40005 0)
			(size 0.4572 0.508)
			(layers "F.Cu" "F.Mask" "F.Paste")
			(net "P52V_HS1_TEMPN_R")
		)
		(pad "2" smd rect
			(at 0.40005 0)
			(size 0.4572 0.508)
			(layers "F.Cu" "F.Mask" "F.Paste")
			(net "GND_FIELD_SIGNAL")
		)
	)
	(footprint ""
		(layer "F.Cu")
		(at 445.741806 -94.799658 180)
		(property "Reference" "PC618"
			(at 0 0 180)
			(layer "F.SilkS")
			(hide yes)
			(effects
				(font
					(size 1.27 1.27)
				)
			)
		)
		(property "Value" ""
			(at 0 0 180)
			(layer "F.Fab")
			(effects
				(font
					(size 1.27 1.27)
				)
			)
		)
		(duplicate_pad_numbers_are_jumpers no)
		(fp_line
			(start 1.524 0.762)
			(end -1.524 0.762)
			(stroke
				(width 0.1524)
				(type default)
			)
			(layer "F.SilkS")
		)
		(fp_line
			(start 1.524 -0.762)
			(end 1.524 0.762)
			(stroke
				(width 0.1524)
				(type default)
			)
			(layer "F.SilkS")
		)
		(fp_line
			(start -1.524 0.762)
			(end -1.524 -0.762)
			(stroke
				(width 0.1524)
				(type default)
			)
			(layer "F.SilkS")
		)
		(fp_line
			(start -1.524 -0.762)
			(end 1.524 -0.762)
			(stroke
				(width 0.1524)
				(type default)
			)
			(layer "F.SilkS")
		)
		(fp_line
			(start 1.1049 0.724916)
			(end 1.1049 -0.724916)
			(stroke
				(width 0.1)
				(type default)
			)
			(layer "F.Fab")
		)
		(fp_line
			(start 1.1049 -0.724916)
			(end -1.1049 -0.724916)
			(stroke
				(width 0.1)
				(type default)
			)
			(layer "F.Fab")
		)
		(fp_line
			(start -1.1049 0.724916)
			(end 1.1049 0.724916)
			(stroke
				(width 0.1)
				(type default)
			)
			(layer "F.Fab")
		)
		(fp_line
			(start -1.1049 -0.724916)
			(end -1.1049 0.724916)
			(stroke
				(width 0.1)
				(type default)
			)
			(layer "F.Fab")
		)
		(pad "1" smd rect
			(at -0.889 0)
			(size 1.016 1.27)
			(layers "F.Cu" "F.Mask" "F.Paste")
			(net "SW_P3V3_HPDB_FLT")
		)
		(pad "2" smd rect
			(at 0.889 0)
			(size 1.016 1.27)
			(layers "F.Cu" "F.Mask" "F.Paste")
			(net "GND")
		)
	)
	(footprint ""
		(layer "F.Cu")
		(at 449.199 -37.211 -90)
		(property "Reference" "R9"
			(at 0 0 270)
			(layer "F.SilkS")
			(hide yes)
			(effects
				(font
					(size 1.27 1.27)
				)
			)
		)
		(property "Value" ""
			(at 0 0 270)
			(layer "F.Fab")
			(effects
				(font
					(size 1.27 1.27)
				)
			)
		)
		(duplicate_pad_numbers_are_jumpers no)
		(fp_line
			(start -0.7874 0.4064)
			(end -0.7874 -0.4064)
			(stroke
				(width 0.1524)
				(type default)
			)
			(layer "F.SilkS")
		)
		(fp_line
			(start 0.7874 0.4064)
			(end -0.7874 0.4064)
			(stroke
				(width 0.1524)
				(type default)
			)
			(layer "F.SilkS")
		)
		(fp_line
			(start -0.7874 -0.4064)
			(end 0.7874 -0.4064)
			(stroke
				(width 0.1524)
				(type default)
			)
			(layer "F.SilkS")
		)
		(fp_line
			(start 0.7874 -0.4064)
			(end 0.7874 0.4064)
			(stroke
				(width 0.1524)
				(type default)
			)
			(layer "F.SilkS")
		)
		(fp_line
			(start -0.67945 0.3048)
			(end -0.67945 -0.305054)
			(stroke
				(width 0.1)
				(type default)
			)
			(layer "F.Fab")
		)
		(fp_line
			(start -0.12065 0.3048)
			(end -0.67945 0.3048)
			(stroke
				(width 0.1)
				(type default)
			)
			(layer "F.Fab")
		)
		(fp_line
			(start 0.120396 0.3048)
			(end 0.120396 0.2794)
			(stroke
				(width 0.1)
				(type default)
			)
			(layer "F.Fab")
		)
		(fp_line
			(start 0.67945 0.3048)
			(end 0.120396 0.3048)
			(stroke
				(width 0.1)
				(type default)
			)
			(layer "F.Fab")
		)
		(fp_line
			(start -0.12065 0.2794)
			(end -0.12065 0.3048)
			(stroke
				(width 0.1)
				(type default)
			)
			(layer "F.Fab")
		)
		(fp_line
			(start 0.120396 0.2794)
			(end -0.12065 0.2794)
			(stroke
				(width 0.1)
				(type default)
			)
			(layer "F.Fab")
		)
		(fp_line
			(start -0.12065 -0.2794)
			(end 0.12065 -0.2794)
			(stroke
				(width 0.1)
				(type default)
			)
			(layer "F.Fab")
		)
		(fp_line
			(start 0.12065 -0.2794)
			(end 0.12065 -0.3048)
			(stroke
				(width 0.1)
				(type default)
			)
			(layer "F.Fab")
		)
		(fp_line
			(start 0.12065 -0.3048)
			(end 0.67945 -0.3048)
			(stroke
				(width 0.1)
				(type default)
			)
			(layer "F.Fab")
		)
		(fp_line
			(start 0.67945 -0.3048)
			(end 0.67945 0.3048)
			(stroke
				(width 0.1)
				(type default)
			)
			(layer "F.Fab")
		)
		(fp_line
			(start -0.67945 -0.305054)
			(end -0.12065 -0.305054)
			(stroke
				(width 0.1)
				(type default)
			)
			(layer "F.Fab")
		)
		(fp_line
			(start -0.12065 -0.305054)
			(end -0.12065 -0.2794)
			(stroke
				(width 0.1)
				(type default)
			)
			(layer "F.Fab")
		)
		(pad "1" smd circle
			(at -0.40005 0 270)
			(size 0 0)
			(layers "F.Cu" "F.Mask" "F.Paste")
			(net "SMB_P52V_PDB_SDA_R")
		)
		(pad "2" smd circle
			(at 0.40005 0 270)
			(size 0 0)
			(layers "F.Cu" "F.Mask" "F.Paste")
			(net "P3V3_AUX")
		)
	)
	(footprint ""
		(layer "F.Cu")
		(at 112.988852 -32.8168 -90)
		(property "Reference" "PR6974"
			(at 0 0 270)
			(layer "F.SilkS")
			(hide yes)
			(effects
				(font
					(size 1.27 1.27)
				)
			)
		)
		(property "Value" ""
			(at 0 0 270)
			(layer "F.Fab")
			(effects
				(font
					(size 1.27 1.27)
				)
			)
		)
		(duplicate_pad_numbers_are_jumpers no)
		(fp_line
			(start -1.2954 0.5842)
			(end -1.2954 -0.5842)
			(stroke
				(width 0.1524)
				(type default)
			)
			(layer "F.SilkS")
		)
		(fp_line
			(start 1.2954 0.5842)
			(end -1.2954 0.5842)
			(stroke
				(width 0.1524)
				(type default)
			)
			(layer "F.SilkS")
		)
		(fp_line
			(start -1.2954 -0.5842)
			(end 1.2954 -0.5842)
			(stroke
				(width 0.1524)
				(type default)
			)
			(layer "F.SilkS")
		)
		(fp_line
			(start 1.2954 -0.5842)
			(end 1.2954 0.5842)
			(stroke
				(width 0.1524)
				(type default)
			)
			(layer "F.SilkS")
		)
		(fp_line
			(start -0.8636 0.4572)
			(end -0.8636 0.4318)
			(stroke
				(width 0.1)
				(type default)
			)
			(layer "F.Fab")
		)
		(fp_line
			(start 0.8636 0.4572)
			(end -0.8636 0.4572)
			(stroke
				(width 0.1)
				(type default)
			)
			(layer "F.Fab")
		)
		(fp_line
			(start -0.8636 0.4318)
			(end -0.8636 0.4064)
			(stroke
				(width 0.1)
				(type default)
			)
			(layer "F.Fab")
		)
		(fp_line
			(start -1.1938 0.4064)
			(end -1.1938 -0.406654)
			(stroke
				(width 0.1)
				(type default)
			)
			(layer "F.Fab")
		)
		(fp_line
			(start -0.8636 0.4064)
			(end -1.1938 0.4064)
			(stroke
				(width 0.1)
				(type default)
			)
			(layer "F.Fab")
		)
		(fp_line
			(start 0.8636 0.4064)
			(end 0.8636 0.4572)
			(stroke
				(width 0.1)
				(type default)
			)
			(layer "F.Fab")
		)
		(fp_line
			(start 1.1938 0.4064)
			(end 0.8636 0.4064)
			(stroke
				(width 0.1)
				(type default)
			)
			(layer "F.Fab")
		)
		(fp_line
			(start -1.1938 -0.406654)
			(end -0.8636 -0.406654)
			(stroke
				(width 0.1)
				(type default)
			)
			(layer "F.Fab")
		)
		(fp_line
			(start -0.8636 -0.406654)
			(end -0.8636 -0.4572)
			(stroke
				(width 0.1)
				(type default)
			)
			(layer "F.Fab")
		)
		(fp_line
			(start 0.8636 -0.406654)
			(end 1.1938 -0.406654)
			(stroke
				(width 0.1)
				(type default)
			)
			(layer "F.Fab")
		)
		(fp_line
			(start 1.1938 -0.406654)
			(end 1.1938 0.4064)
			(stroke
				(width 0.1)
				(type default)
			)
			(layer "F.Fab")
		)
		(fp_line
			(start -0.8636 -0.4572)
			(end 0.8636 -0.4572)
			(stroke
				(width 0.1)
				(type default)
			)
			(layer "F.Fab")
		)
		(fp_line
			(start 0.8636 -0.4572)
			(end 0.8636 -0.406654)
			(stroke
				(width 0.1)
				(type default)
			)
			(layer "F.Fab")
		)
		(pad "1" smd rect
			(at -0.7366 0 180)
			(size 0.7112 0.8128)
			(layers "F.Cu" "F.Mask" "F.Paste")
			(net "P52V_HS2_GATE2_R")
		)
		(pad "2" smd rect
			(at 0.7366 0 180)
			(size 0.7112 0.8128)
			(layers "F.Cu" "F.Mask" "F.Paste")
			(net "P52V_HS2_GATE5")
		)
	)
	(footprint ""
		(layer "F.Cu")
		(at 307.969412 -76.245974)
		(property "Reference" "H26"
			(at -1.1684 -3.52933 0)
			(unlocked yes)
			(layer "F.SilkS")
			(effects
				(font
					(size 0.7874 0.5842)
					(thickness 0.1524)
				)
				(justify left)
			)
		)
		(property "Value" ""
			(at 0 0 0)
			(layer "F.Fab")
			(effects
				(font
					(size 1.27 1.27)
				)
			)
		)
		(duplicate_pad_numbers_are_jumpers no)
		(fp_circle
			(center 0 0)
			(end 2.4003 0)
			(stroke
				(width 0.1524)
				(type default)
			)
			(fill no)
			(layer "F.SilkS")
		)
		(fp_circle
			(center 0 0)
			(end 6.5913 0)
			(stroke
				(width 0.1524)
				(type default)
			)
			(fill no)
			(layer "B.SilkS")
		)
		(fp_circle
			(center 0 0)
			(end 6.5913 0)
			(stroke
				(width 0.1)
				(type default)
			)
			(fill no)
			(layer "B.Fab")
		)
		(fp_circle
			(center 0 0)
			(end 2.4003 0)
			(stroke
				(width 0.1)
				(type default)
			)
			(fill no)
			(layer "F.Fab")
		)
		(pad "" np_thru_hole circle
			(at 0 0)
			(size 3.175 3.175)
			(drill 3.175)
			(layers "*.Cu" "*.Mask")
			(clearance 0.381)
			(thermal_gap 0.381)
		)
		(zone
			(layers "F.Cu" "B.Cu" "In1.Cu" "In2.Cu" "In3.Cu" "In4.Cu" "In5.Cu" "In6.Cu"
				"In7.Cu" "In8.Cu"
			)
			(hatch none 0.5)
			(connect_pads
				(clearance 0)
			)
			(min_thickness 0.25)
			(keepout
				(tracks not_allowed)
				(vias allowed)
				(pads allowed)
				(copperpour not_allowed)
				(footprints allowed)
			)
			(placement
				(enabled no)
				(sheetname "")
			)
			(fill
				(thermal_gap 0.5)
				(thermal_bridge_width 0.5)
				(island_removal_mode 0)
			)
			(polygon
				(pts
					(arc
						(start 310.064912 -76.245974)
						(mid 305.873912 -76.245974)
						(end 310.064912 -76.245974)
					)
				)
			)
		)
	)
	(footprint ""
		(layer "F.Cu")
		(at 449.39712 -81.95818)
		(property "Reference" "PR111"
			(at 0 0 0)
			(layer "F.SilkS")
			(hide yes)
			(effects
				(font
					(size 1.27 1.27)
				)
			)
		)
		(property "Value" ""
			(at 0 0 0)
			(layer "F.Fab")
			(effects
				(font
					(size 1.27 1.27)
				)
			)
		)
		(duplicate_pad_numbers_are_jumpers no)
		(fp_line
			(start -0.7874 -0.4064)
			(end 0.7874 -0.4064)
			(stroke
				(width 0.1524)
				(type default)
			)
			(layer "F.SilkS")
		)
		(fp_line
			(start -0.7874 0.4064)
			(end -0.7874 -0.4064)
			(stroke
				(width 0.1524)
				(type default)
			)
			(layer "F.SilkS")
		)
		(fp_line
			(start 0.7874 -0.4064)
			(end 0.7874 0.4064)
			(stroke
				(width 0.1524)
				(type default)
			)
			(layer "F.SilkS")
		)
		(fp_line
			(start 0.7874 0.4064)
			(end -0.7874 0.4064)
			(stroke
				(width 0.1524)
				(type default)
			)
			(layer "F.SilkS")
		)
		(fp_line
			(start -0.67945 -0.305054)
			(end -0.12065 -0.305054)
			(stroke
				(width 0.1)
				(type default)
			)
			(layer "F.Fab")
		)
		(fp_line
			(start -0.67945 0.3048)
			(end -0.67945 -0.305054)
			(stroke
				(width 0.1)
				(type default)
			)
			(layer "F.Fab")
		)
		(fp_line
			(start -0.12065 -0.305054)
			(end -0.12065 -0.2794)
			(stroke
				(width 0.1)
				(type default)
			)
			(layer "F.Fab")
		)
		(fp_line
			(start -0.12065 -0.2794)
			(end 0.12065 -0.2794)
			(stroke
				(width 0.1)
				(type default)
			)
			(layer "F.Fab")
		)
		(fp_line
			(start -0.12065 0.2794)
			(end -0.12065 0.3048)
			(stroke
				(width 0.1)
				(type default)
			)
			(layer "F.Fab")
		)
		(fp_line
			(start -0.12065 0.3048)
			(end -0.67945 0.3048)
			(stroke
				(width 0.1)
				(type default)
			)
			(layer "F.Fab")
		)
		(fp_line
			(start 0.120396 0.2794)
			(end -0.12065 0.2794)
			(stroke
				(width 0.1)
				(type default)
			)
			(layer "F.Fab")
		)
		(fp_line
			(start 0.120396 0.3048)
			(end 0.120396 0.2794)
			(stroke
				(width 0.1)
				(type default)
			)
			(layer "F.Fab")
		)
		(fp_line
			(start 0.12065 -0.3048)
			(end 0.67945 -0.3048)
			(stroke
				(width 0.1)
				(type default)
			)
			(layer "F.Fab")
		)
		(fp_line
			(start 0.12065 -0.2794)
			(end 0.12065 -0.3048)
			(stroke
				(width 0.1)
				(type default)
			)
			(layer "F.Fab")
		)
		(fp_line
			(start 0.67945 -0.3048)
			(end 0.67945 0.3048)
			(stroke
				(width 0.1)
				(type default)
			)
			(layer "F.Fab")
		)
		(fp_line
			(start 0.67945 0.3048)
			(end 0.120396 0.3048)
			(stroke
				(width 0.1)
				(type default)
			)
			(layer "F.Fab")
		)
		(pad "1" smd circle
			(at -0.40005 0)
			(size 0 0)
			(layers "F.Cu" "F.Mask" "F.Paste")
			(net "SW_P3V3_HPDB_BT")
		)
		(pad "2" smd circle
			(at 0.40005 0)
			(size 0 0)
			(layers "F.Cu" "F.Mask" "F.Paste")
			(net "SW_P3V3_HPDB_BT_R")
		)
	)
)
